(kicad_pcb
	(version 20260206)
	(generator "pcbnew")
	(generator_version "10.0")
	(general
		(thickness 1.6)
		(legacy_teardrops no)
	)
	(paper "A4")
	(title_block
		(title "Wiwynn_Tioga_Pass_MB.brd")
		(comment 1 "Tioga Pass / footprint 2035 of 4770 (U8D7), pads 109-217 of 256")
	)
	(layers
		(0 "F.Cu" signal "TOP")
		(4 "In1.Cu" signal "L2GND")
		(6 "In2.Cu" signal "L3")
		(8 "In3.Cu" signal "L4GND")
		(10 "In4.Cu" signal "L5")
		(12 "In5.Cu" signal "L6GND")
		(14 "In6.Cu" signal "L7VCC")
		(16 "In7.Cu" signal "L8VCC")
		(18 "In8.Cu" signal "L9GND")
		(20 "In9.Cu" signal "L10")
		(22 "In10.Cu" signal "L11GND")
		(24 "In11.Cu" signal "L12")
		(26 "In12.Cu" signal "L13GND")
		(2 "B.Cu" signal "BOTTOM")
		(9 "F.Adhes" user "F.Adhesive")
		(11 "B.Adhes" user "B.Adhesive")
		(13 "F.Paste" user "Package Geometry/Pastemask Top")
		(15 "B.Paste" user "Package Geometry/Pastemask Bottom")
		(5 "F.SilkS" user "Ref Des/Silkscreen Top")
		(7 "B.SilkS" user "Ref Des/Silkscreen Bottom")
		(1 "F.Mask" user "Board Geometry/Soldermask Top")
		(3 "B.Mask" user "Board Geometry/Soldermask Bottom")
		(17 "Dwgs.User" user "User.Drawings")
		(19 "Cmts.User" user "User.Comments")
		(21 "Eco1.User" user "User.Eco1")
		(23 "Eco2.User" user "User.Eco2")
		(25 "Edge.Cuts" user "Board Geometry/Outline")
		(27 "Margin" user)
		(31 "F.CrtYd" user "Package Geometry/Place Bound Top")
		(29 "B.CrtYd" user "Package Geometry/Place Bound Bottom")
		(35 "F.Fab" user "Ref Des/Assembly Top")
		(33 "B.Fab" user "Ref Des/Assembly Bottom")
	)
	(footprint ""
		(layer "F.Cu")
		(at 372.745 -74.295 180)
		(property "Reference" "U8D7"
			(at -0.635 -8.28167 0)
			(unlocked yes)
			(layer "F.SilkS")
			(effects
				(font
					(size 0.7874 0.5842)
					(thickness 0.1524)
				)
			)
		)
		(property "Value" ""
			(at 0 0 180)
			(layer "F.Fab")
			(effects
				(font
					(size 1.27 1.27)
				)
			)
		)
		(duplicate_pad_numbers_are_jumpers no)
		(pad "G13" smd circle
			(at 3.599942 -1.199896 180)
			(size 0.3556 0.3556)
			(layers "F.Cu" "F.Mask" "F.Paste")
			(net "FM_CPU1_FIVR_FAULT_LVT3")
		)
		(pad "G14" smd circle
			(at 4.400042 -1.199896 180)
			(size 0.3556 0.3556)
			(layers "F.Cu" "F.Mask" "F.Paste")
			(net "FM_CPU1_THERMTRIP_LVT3_N")
		)
		(pad "G15" smd circle
			(at 5.199888 -1.199896 180)
			(size 0.3556 0.3556)
			(layers "F.Cu" "F.Mask" "F.Paste")
			(net "FM_UV_ADR_TRIGGER_N")
		)
		(pad "G16" smd circle
			(at 5.999988 -1.199896 180)
			(size 0.3556 0.3556)
			(layers "F.Cu" "F.Mask" "F.Paste")
			(net "FM_FAST_PROCHOT_THROTTLE_IN_N")
		)
		(pad "H1" smd circle
			(at -5.999988 -0.40005 180)
			(size 0.3556 0.3556)
			(layers "F.Cu" "F.Mask" "F.Paste")
			(net "RST_PCIE_CPU_DEV3_N")
		)
		(pad "H2" smd circle
			(at -5.199888 -0.40005 180)
			(size 0.3556 0.3556)
			(layers "F.Cu" "F.Mask" "F.Paste")
			(net "FM_PVCCMCP_CPU0_EN")
		)
		(pad "H3" smd circle
			(at -4.400042 -0.40005 180)
			(size 0.3556 0.3556)
			(layers "F.Cu" "F.Mask" "F.Paste")
			(net "RST_PCIE_CPU_DEV2_N")
		)
		(pad "H4" smd circle
			(at -3.599942 -0.40005 180)
			(size 0.3556 0.3556)
			(layers "F.Cu" "F.Mask" "F.Paste")
			(net "FM_MP_PS_FAIL_N")
		)
		(pad "H5" smd circle
			(at -2.800096 -0.40005 180)
			(size 0.3556 0.3556)
			(layers "F.Cu" "F.Mask" "F.Paste")
			(net "Net_480")
		)
		(pad "H6" smd circle
			(at -1.999996 -0.40005 180)
			(size 0.3556 0.3556)
			(layers "F.Cu" "F.Mask" "F.Paste")
			(net "PWRGD_P3V3")
		)
		(pad "H7" smd circle
			(at -1.199896 -0.40005 180)
			(size 0.3556 0.3556)
			(layers "F.Cu" "F.Mask" "F.Paste")
			(net "P3V3_STBY")
		)
		(pad "H8" smd circle
			(at -0.40005 -0.40005 180)
			(size 0.3556 0.3556)
			(layers "F.Cu" "F.Mask" "F.Paste")
			(net "GND")
		)
		(pad "H9" smd circle
			(at 0.40005 -0.40005 180)
			(size 0.3556 0.3556)
			(layers "F.Cu" "F.Mask" "F.Paste")
			(net "GND")
		)
		(pad "H10" smd circle
			(at 1.199896 -0.40005 180)
			(size 0.3556 0.3556)
			(layers "F.Cu" "F.Mask" "F.Paste")
			(net "P3V3_STBY")
		)
		(pad "H11" smd circle
			(at 1.999996 -0.40005 180)
			(size 0.3556 0.3556)
			(layers "F.Cu" "F.Mask" "F.Paste")
			(net "TP_CPLD1_PR9C")
		)
		(pad "H12" smd circle
			(at 2.800096 -0.40005 180)
			(size 0.3556 0.3556)
			(layers "F.Cu" "F.Mask" "F.Paste")
			(net "FM_UV_ADR_TRIGGER_EN")
		)
		(pad "H13" smd circle
			(at 3.599942 -0.40005 180)
			(size 0.3556 0.3556)
			(layers "F.Cu" "F.Mask" "F.Paste")
			(net "FM_PVDDQ_GHJ_EN")
		)
		(pad "H14" smd circle
			(at 4.400042 -0.40005 180)
			(size 0.3556 0.3556)
			(layers "F.Cu" "F.Mask" "F.Paste")
			(net "TP_CPLD1_PR7A_PCLKT1_0")
		)
		(pad "H15" smd circle
			(at 5.199888 -0.40005 180)
			(size 0.3556 0.3556)
			(layers "F.Cu" "F.Mask" "F.Paste")
			(net "FM_PVDDQ_KLM_EN")
		)
		(pad "H16" smd circle
			(at 5.999988 -0.40005 180)
			(size 0.3556 0.3556)
			(layers "F.Cu" "F.Mask" "F.Paste")
			(net "TP_CPLD1_PR7B_PCLKC1_0")
		)
		(pad "J1" smd circle
			(at -5.999988 0.40005 180)
			(size 0.3556 0.3556)
			(layers "F.Cu" "F.Mask" "F.Paste")
			(net "SGPIO_BMC_CLK")
		)
		(pad "J2" smd circle
			(at -5.199888 0.40005 180)
			(size 0.3556 0.3556)
			(layers "F.Cu" "F.Mask" "F.Paste")
			(net "SGPIO_BMC_DOUT")
		)
		(pad "J3" smd circle
			(at -4.400042 0.40005 180)
			(size 0.3556 0.3556)
			(layers "F.Cu" "F.Mask" "F.Paste")
			(net "TP_CPLD1_PL7D_PCLKT4_0")
		)
		(pad "J4" smd circle
			(at -3.599942 0.40005 180)
			(size 0.3556 0.3556)
			(layers "F.Cu" "F.Mask" "F.Paste")
			(net "Net_481")
		)
		(pad "J5" smd circle
			(at -2.800096 0.40005 180)
			(size 0.3556 0.3556)
			(layers "F.Cu" "F.Mask" "F.Paste")
			(net "UART_BMC_RXD5")
		)
		(pad "J6" smd circle
			(at -1.999996 0.40005 180)
			(size 0.3556 0.3556)
			(layers "F.Cu" "F.Mask" "F.Paste")
			(net "PWRGD_P5V")
		)
		(pad "J7" smd circle
			(at -1.199896 0.40005 180)
			(size 0.3556 0.3556)
			(layers "F.Cu" "F.Mask" "F.Paste")
			(net "P3V3_STBY")
		)
		(pad "J8" smd circle
			(at -0.40005 0.40005 180)
			(size 0.3556 0.3556)
			(layers "F.Cu" "F.Mask" "F.Paste")
			(net "GND")
		)
		(pad "J9" smd circle
			(at 0.40005 0.40005 180)
			(size 0.3556 0.3556)
			(layers "F.Cu" "F.Mask" "F.Paste")
			(net "GND")
		)
		(pad "J10" smd circle
			(at 1.199896 0.40005 180)
			(size 0.3556 0.3556)
			(layers "F.Cu" "F.Mask" "F.Paste")
			(net "P3V3_STBY")
		)
		(pad "J11" smd circle
			(at 1.999996 0.40005 180)
			(size 0.3556 0.3556)
			(layers "F.Cu" "F.Mask" "F.Paste")
			(net "TP_CPLD1_PR10C")
		)
		(pad "J12" smd circle
			(at 2.800096 0.40005 180)
			(size 0.3556 0.3556)
			(layers "F.Cu" "F.Mask" "F.Paste")
			(net "FM_FAST_PROCHOT_THROTTLE_DLY_N")
		)
		(pad "J13" smd circle
			(at 3.599942 0.40005 180)
			(size 0.3556 0.3556)
			(layers "F.Cu" "F.Mask" "F.Paste")
			(net "TP_CPLD1_PR9D")
		)
		(pad "J14" smd circle
			(at 4.400042 0.40005 180)
			(size 0.3556 0.3556)
			(layers "F.Cu" "F.Mask" "F.Paste")
			(net "TP_CPLD1_PR7D")
		)
		(pad "J15" smd circle
			(at 5.199888 0.40005 180)
			(size 0.3556 0.3556)
			(layers "F.Cu" "F.Mask" "F.Paste")
			(net "TP_CPLD1_PR9A")
		)
		(pad "J16" smd circle
			(at 5.999988 0.40005 180)
			(size 0.3556 0.3556)
			(layers "F.Cu" "F.Mask" "F.Paste")
			(net "TP_CPLD1_PR7C")
		)
		(pad "K1" smd circle
			(at -5.999988 1.199896 180)
			(size 0.3556 0.3556)
			(layers "F.Cu" "F.Mask" "F.Paste")
			(net "FM_PVCCIOMCP_CPU0_EN")
		)
		(pad "K2" smd circle
			(at -5.199888 1.199896 180)
			(size 0.3556 0.3556)
			(layers "F.Cu" "F.Mask" "F.Paste")
			(net "SP1_BMC_HOST_UART_TX")
		)
		(pad "K3" smd circle
			(at -4.400042 1.199896 180)
			(size 0.3556 0.3556)
			(layers "F.Cu" "F.Mask" "F.Paste")
			(net "SP1_BMC_HOST_UART_RX")
		)
		(pad "K4" smd circle
			(at -3.599942 1.199896 180)
			(size 0.3556 0.3556)
			(layers "F.Cu" "F.Mask" "F.Paste")
			(net "SGPIO_BMC_LD_N")
		)
		(pad "K5" smd circle
			(at -2.800096 1.199896 180)
			(size 0.3556 0.3556)
			(layers "F.Cu" "F.Mask" "F.Paste")
			(net "PWRGD_PVCCIN_CPU0")
		)
		(pad "K6" smd circle
			(at -1.999996 1.199896 180)
			(size 0.3556 0.3556)
			(layers "F.Cu" "F.Mask" "F.Paste")
			(net "UART_BMC_TXD5")
		)
		(pad "K7" smd circle
			(at -1.199896 1.199896 180)
			(size 0.3556 0.3556)
			(layers "F.Cu" "F.Mask" "F.Paste")
			(net "P3V3_STBY")
		)
		(pad "K8" smd circle
			(at -0.40005 1.199896 180)
			(size 0.3556 0.3556)
			(layers "F.Cu" "F.Mask" "F.Paste")
			(net "P3V3_STBY")
		)
		(pad "K9" smd circle
			(at 0.40005 1.199896 180)
			(size 0.3556 0.3556)
			(layers "F.Cu" "F.Mask" "F.Paste")
			(net "P3V3_STBY")
		)
		(pad "K10" smd circle
			(at 1.199896 1.199896 180)
			(size 0.3556 0.3556)
			(layers "F.Cu" "F.Mask" "F.Paste")
			(net "P3V3_STBY")
		)
		(pad "K11" smd circle
			(at 1.999996 1.199896 180)
			(size 0.3556 0.3556)
			(layers "F.Cu" "F.Mask" "F.Paste")
			(net "RST_PLTRST_BUF_N")
		)
		(pad "K12" smd circle
			(at 2.800096 1.199896 180)
			(size 0.3556 0.3556)
			(layers "F.Cu" "F.Mask" "F.Paste")
			(net "FM_MEM_THERM_EVENT_PCH_N")
		)
		(pad "K13" smd circle
			(at 3.599942 1.199896 180)
			(size 0.3556 0.3556)
			(layers "F.Cu" "F.Mask" "F.Paste")
			(net "FM_MEM_THERM_EVENT_LVT3_N")
		)
		(pad "K14" smd circle
			(at 4.400042 1.199896 180)
			(size 0.3556 0.3556)
			(layers "F.Cu" "F.Mask" "F.Paste")
			(net "FM_PVDDQ_ABC_EN")
		)
		(pad "K15" smd circle
			(at 5.199888 1.199896 180)
			(size 0.3556 0.3556)
			(layers "F.Cu" "F.Mask" "F.Paste")
			(net "FM_PVDDQ_DEF_EN")
		)
		(pad "K16" smd circle
			(at 5.999988 1.199896 180)
			(size 0.3556 0.3556)
			(layers "F.Cu" "F.Mask" "F.Paste")
			(net "PU_FAB2_MARKER_CPLD")
		)
		(pad "L1" smd circle
			(at -5.999988 1.999996 180)
			(size 0.3556 0.3556)
			(layers "F.Cu" "F.Mask" "F.Paste")
			(net "PWRGD_PVSA_CPU0")
		)
		(pad "L2" smd circle
			(at -5.199888 1.999996 180)
			(size 0.3556 0.3556)
			(layers "F.Cu" "F.Mask" "F.Paste")
			(net "CLK_25M_CPLD")
		)
		(pad "L3" smd circle
			(at -4.400042 1.999996 180)
			(size 0.3556 0.3556)
			(layers "F.Cu" "F.Mask" "F.Paste")
			(net "TP_CPLD1_PL11A")
		)
		(pad "L4" smd circle
			(at -3.599942 1.999996 180)
			(size 0.3556 0.3556)
			(layers "F.Cu" "F.Mask" "F.Paste")
			(net "PWRGD_PVCCMCP_CPU1")
		)
		(pad "L5" smd circle
			(at -2.800096 1.999996 180)
			(size 0.3556 0.3556)
			(layers "F.Cu" "F.Mask" "F.Paste")
			(net "PWRGD_CPU0_LVC3")
		)
		(pad "L6" smd circle
			(at -1.999996 1.999996 180)
			(size 0.3556 0.3556)
			(layers "F.Cu" "F.Mask" "F.Paste")
			(net "GND")
		)
		(pad "L7" smd circle
			(at -1.199896 1.999996 180)
			(size 0.3556 0.3556)
			(layers "F.Cu" "F.Mask" "F.Paste")
			(net "FM_OC0_USB_N")
		)
		(pad "L8" smd circle
			(at -0.40005 1.999996 180)
			(size 0.3556 0.3556)
			(layers "F.Cu" "F.Mask" "F.Paste")
			(net "PWRGD_PVCCIO_CPU0")
		)
		(pad "L9" smd circle
			(at 0.40005 1.999996 180)
			(size 0.3556 0.3556)
			(layers "F.Cu" "F.Mask" "F.Paste")
			(net "FM_IE_DISABLE_N")
		)
		(pad "L10" smd circle
			(at 1.199896 1.999996 180)
			(size 0.3556 0.3556)
			(layers "F.Cu" "F.Mask" "F.Paste")
			(net "FM_SOL_UART_CH_SEL")
		)
		(pad "L11" smd circle
			(at 1.999996 1.999996 180)
			(size 0.3556 0.3556)
			(layers "F.Cu" "F.Mask" "F.Paste")
			(net "GND")
		)
		(pad "L12" smd circle
			(at 2.800096 1.999996 180)
			(size 0.3556 0.3556)
			(layers "F.Cu" "F.Mask" "F.Paste")
			(net "PWRGD_P3V3_STBY")
		)
		(pad "L13" smd circle
			(at 3.599942 1.999996 180)
			(size 0.3556 0.3556)
			(layers "F.Cu" "F.Mask" "F.Paste")
			(net "TP_CPLD1_PR12D")
		)
		(pad "L14" smd circle
			(at 4.400042 1.999996 180)
			(size 0.3556 0.3556)
			(layers "F.Cu" "F.Mask" "F.Paste")
			(net "TP_CPLD1_PR11B")
		)
		(pad "L15" smd circle
			(at 5.199888 1.999996 180)
			(size 0.3556 0.3556)
			(layers "F.Cu" "F.Mask" "F.Paste")
			(net "FM_THERMTRIP_DLY")
		)
		(pad "L16" smd circle
			(at 5.999988 1.999996 180)
			(size 0.3556 0.3556)
			(layers "F.Cu" "F.Mask" "F.Paste")
			(net "PWRGD_PVCCIO_CPU1")
		)
		(pad "M1" smd circle
			(at -5.999988 2.800096 180)
			(size 0.3556 0.3556)
			(layers "F.Cu" "F.Mask" "F.Paste")
			(net "RST_RSMRST_DLY")
		)
		(pad "M2" smd circle
			(at -5.199888 2.800096 180)
			(size 0.3556 0.3556)
			(layers "F.Cu" "F.Mask" "F.Paste")
			(net "PWRGD_PVPP_GHJ")
		)
		(pad "M3" smd circle
			(at -4.400042 2.800096 180)
			(size 0.3556 0.3556)
			(layers "F.Cu" "F.Mask" "F.Paste")
			(net "RST_PCIE_RISER1_PERST_N")
		)
		(pad "M4" smd circle
			(at -3.599942 2.800096 180)
			(size 0.3556 0.3556)
			(layers "F.Cu" "F.Mask" "F.Paste")
			(net "P3V3_STBY")
		)
		(pad "M5" smd circle
			(at -2.800096 2.800096 180)
			(size 0.3556 0.3556)
			(layers "F.Cu" "F.Mask" "F.Paste")
			(net "GND")
		)
		(pad "M6" smd circle
			(at -1.999996 2.800096 180)
			(size 0.3556 0.3556)
			(layers "F.Cu" "F.Mask" "F.Paste")
			(net "PWRGD_PVPP_DEF")
		)
		(pad "M7" smd circle
			(at -1.199896 2.800096 180)
			(size 0.3556 0.3556)
			(layers "F.Cu" "F.Mask" "F.Paste")
			(net "FM_PVCCIO_CPU0_EN")
		)
		(pad "M8" smd circle
			(at -0.40005 2.800096 180)
			(size 0.3556 0.3556)
			(layers "F.Cu" "F.Mask" "F.Paste")
			(net "FM_PVCCMCP_CPU1_EN")
		)
		(pad "M9" smd circle
			(at 0.40005 2.800096 180)
			(size 0.3556 0.3556)
			(layers "F.Cu" "F.Mask" "F.Paste")
			(net "FM_CPLD_UART_CH_LOCK_N")
		)
		(pad "M10" smd circle
			(at 1.199896 2.800096 180)
			(size 0.3556 0.3556)
			(layers "F.Cu" "F.Mask" "F.Paste")
			(net "PWRGD_CPU1_LVC3")
		)
		(pad "M11" smd circle
			(at 1.999996 2.800096 180)
			(size 0.3556 0.3556)
			(layers "F.Cu" "F.Mask" "F.Paste")
			(net "XDP_PWRGD_RST_N")
		)
		(pad "M12" smd circle
			(at 2.800096 2.800096 180)
			(size 0.3556 0.3556)
			(layers "F.Cu" "F.Mask" "F.Paste")
			(net "GND")
		)
		(pad "M13" smd circle
			(at 3.599942 2.800096 180)
			(size 0.3556 0.3556)
			(layers "F.Cu" "F.Mask" "F.Paste")
			(net "P3V3_STBY")
		)
		(pad "M14" smd circle
			(at 4.400042 2.800096 180)
			(size 0.3556 0.3556)
			(layers "F.Cu" "F.Mask" "F.Paste")
			(net "FM_CPU1_PROC_ID1")
		)
		(pad "M15" smd circle
			(at 5.199888 2.800096 180)
			(size 0.3556 0.3556)
			(layers "F.Cu" "F.Mask" "F.Paste")
			(net "FM_CPU1_PROC_ID0")
		)
		(pad "M16" smd circle
			(at 5.999988 2.800096 180)
			(size 0.3556 0.3556)
			(layers "F.Cu" "F.Mask" "F.Paste")
			(net "FM_CPU0_FIVR_FAULT_LVT3")
		)
		(pad "N1" smd circle
			(at -5.999988 3.599942 180)
			(size 0.3556 0.3556)
			(layers "F.Cu" "F.Mask" "F.Paste")
			(net "PWRGD_PVCCIN_CPU1")
		)
		(pad "N2" smd circle
			(at -5.199888 3.599942 180)
			(size 0.3556 0.3556)
			(layers "F.Cu" "F.Mask" "F.Paste")
			(net "PWRGD_PVPP_KLM")
		)
		(pad "N3" smd circle
			(at -4.400042 3.599942 180)
			(size 0.3556 0.3556)
			(layers "F.Cu" "F.Mask" "F.Paste")
			(net "RST_CD_CPU0_POR_N")
		)
		(pad "N4" smd circle
			(at -3.599942 3.599942 180)
			(size 0.3556 0.3556)
			(layers "F.Cu" "F.Mask" "F.Paste")
			(net "GND")
		)
		(pad "N5" smd circle
			(at -2.800096 3.599942 180)
			(size 0.3556 0.3556)
			(layers "F.Cu" "F.Mask" "F.Paste")
			(net "P3V3_STBY")
		)
		(pad "N6" smd circle
			(at -1.999996 3.599942 180)
			(size 0.3556 0.3556)
			(layers "F.Cu" "F.Mask" "F.Paste")
			(net "PWRGD_PVCCIOMCP_CPU0")
		)
		(pad "N7" smd circle
			(at -1.199896 3.599942 180)
			(size 0.3556 0.3556)
			(layers "F.Cu" "F.Mask" "F.Paste")
			(net "PWRGD_PVPP_ABC")
		)
		(pad "N8" smd circle
			(at -0.40005 3.599942 180)
			(size 0.3556 0.3556)
			(layers "F.Cu" "F.Mask" "F.Paste")
			(net "FM_156M_CPU1_BRD_OSC_EN")
		)
		(pad "N9" smd circle
			(at 0.40005 3.599942 180)
			(size 0.3556 0.3556)
			(layers "F.Cu" "F.Mask" "F.Paste")
			(net "FM_CPLD_BMC_PWRDN_N")
		)
		(pad "N10" smd circle
			(at 1.199896 3.599942 180)
			(size 0.3556 0.3556)
			(layers "F.Cu" "F.Mask" "F.Paste")
			(net "RST_CPU1_LVC3_R1_N")
		)
		(pad "N11" smd circle
			(at 1.999996 3.599942 180)
			(size 0.3556 0.3556)
			(layers "F.Cu" "F.Mask" "F.Paste")
			(net "XDP_SYSPWROK")
		)
		(pad "N12" smd circle
			(at 2.800096 3.599942 180)
			(size 0.3556 0.3556)
			(layers "F.Cu" "F.Mask" "F.Paste")
			(net "P3V3_STBY")
		)
		(pad "N13" smd circle
			(at 3.599942 3.599942 180)
			(size 0.3556 0.3556)
			(layers "F.Cu" "F.Mask" "F.Paste")
			(net "GND")
		)
		(pad "N14" smd circle
			(at 4.400042 3.599942 180)
			(size 0.3556 0.3556)
			(layers "F.Cu" "F.Mask" "F.Paste")
			(net "FM_CPU1_VRM_OSC_EN")
		)
		(pad "N15" smd circle
			(at 5.199888 3.599942 180)
			(size 0.3556 0.3556)
			(layers "F.Cu" "F.Mask" "F.Paste")
			(net "FM_CPU0_THERMTRIP_LVT3_N")
		)
		(pad "N16" smd circle
			(at 5.999988 3.599942 180)
			(size 0.3556 0.3556)
			(layers "F.Cu" "F.Mask" "F.Paste")
			(net "FM_PVCCIN_PVCCSA_CPU1_EN_LVC1")
		)
		(pad "P1" smd circle
			(at -5.999988 4.400042 180)
			(size 0.3556 0.3556)
			(layers "F.Cu" "F.Mask" "F.Paste")
			(net "FM_GLOBAL_RST_WARN_N")
		)
		(pad "P2" smd circle
			(at -5.199888 4.400042 180)
			(size 0.3556 0.3556)
			(layers "F.Cu" "F.Mask" "F.Paste")
			(net "FM_UART_ALERT_N")
		)
		(pad "P3" smd circle
			(at -4.400042 4.400042 180)
			(size 0.3556 0.3556)
			(layers "F.Cu" "F.Mask" "F.Paste")
			(net "GND")
		)
		(pad "P4" smd circle
			(at -3.599942 4.400042 180)
			(size 0.3556 0.3556)
			(layers "F.Cu" "F.Mask" "F.Paste")
			(net "FM_CPU1_RC_EN")
		)
		(pad "P5" smd circle
			(at -2.800096 4.400042 180)
			(size 0.3556 0.3556)
			(layers "F.Cu" "F.Mask" "F.Paste")
			(net "PWRGD_PVCCMCP_CPU0")
		)
		(pad "P6" smd circle
			(at -1.999996 4.400042 180)
			(size 0.3556 0.3556)
			(layers "F.Cu" "F.Mask" "F.Paste")
			(net "TP_CPLD1_PB8A_MCLK_CCLK")
		)
		(pad "P7" smd circle
			(at -1.199896 4.400042 180)
			(size 0.3556 0.3556)
			(layers "F.Cu" "F.Mask" "F.Paste")
			(net "FM_PVCCIOMCP_CPU1_EN")
		)
		(pad "P8" smd circle
			(at -0.40005 4.400042 180)
			(size 0.3556 0.3556)
			(layers "F.Cu" "F.Mask" "F.Paste")
			(net "PWRGD_PVNN_P1V05_PCH")
		)
		(pad "P9" smd circle
			(at 0.40005 4.400042 180)
			(size 0.3556 0.3556)
			(layers "F.Cu" "F.Mask" "F.Paste")
			(net "TP_CPLD1_PB16B_PCLKC2_1")
		)
	)
)
